(kicad_pcb
	(version 20260206)
	(generator "pcbnew")
	(generator_version "10.0")
	(general
		(thickness 1.6)
		(legacy_teardrops no)
	)
	(paper "A4")
	(title_block
		(title "v1-chassis-manager — T6M_CM_d_v01_1031_1645.brd")
		(comment 1 "Open CloudServer (Microsoft) / footprints 504-511 of 2512")
	)
	(layers
		(0 "F.Cu" signal "TOP")
		(4 "In1.Cu" signal "GND1")
		(6 "In2.Cu" signal "IN1")
		(8 "In3.Cu" signal "VCC1")
		(10 "In4.Cu" signal "VCC2")
		(12 "In5.Cu" signal "GND2")
		(14 "In6.Cu" signal "IN2")
		(16 "In7.Cu" signal "IN3")
		(18 "In8.Cu" signal "GND3")
		(2 "B.Cu" signal "BOTTOM")
		(9 "F.Adhes" user "F.Adhesive")
		(11 "B.Adhes" user "B.Adhesive")
		(13 "F.Paste" user "Package Geometry/Pastemask Top")
		(15 "B.Paste" user "Package Geometry/Pastemask Bottom")
		(5 "F.SilkS" user "Ref Des/Silkscreen Top")
		(7 "B.SilkS" user "Ref Des/Silkscreen Bottom")
		(1 "F.Mask" user "Board Geometry/Soldermask Top")
		(3 "B.Mask" user "Board Geometry/Soldermask Bottom")
		(17 "Dwgs.User" user "User.Drawings")
		(19 "Cmts.User" user "User.Comments")
		(21 "Eco1.User" user "User.Eco1")
		(23 "Eco2.User" user "User.Eco2")
		(25 "Edge.Cuts" user "Board Geometry/Outline")
		(27 "Margin" user)
		(31 "F.CrtYd" user "Package Geometry/Place Bound Top")
		(29 "B.CrtYd" user "Package Geometry/Place Bound Bottom")
		(35 "F.Fab" user "Ref Des/Assembly Top")
		(33 "B.Fab" user "Ref Des/Assembly Bottom")
	)
	(footprint ""
		(layer "F.Cu")
		(at 44.36618 -112.963706)
		(property "Reference" "PC14"
			(at 0.63246 -1.265936 90)
			(unlocked yes)
			(layer "F.SilkS")
			(effects
				(font
					(size 0.7874 0.5842)
					(thickness 0.1524)
				)
				(justify left)
			)
		)
		(property "Value" ""
			(at 0 0 0)
			(layer "F.Fab")
			(effects
				(font
					(size 1.27 1.27)
				)
			)
		)
		(duplicate_pad_numbers_are_jumpers no)
		(fp_line
			(start -0.7874 -0.4064)
			(end 0.7874 -0.4064)
			(stroke
				(width 0.1524)
				(type default)
			)
			(layer "F.SilkS")
		)
		(fp_line
			(start -0.7874 0.4064)
			(end -0.7874 -0.4064)
			(stroke
				(width 0.1524)
				(type default)
			)
			(layer "F.SilkS")
		)
		(fp_line
			(start 0 0.381)
			(end 0 -0.381)
			(stroke
				(width 0.1524)
				(type default)
			)
			(layer "F.SilkS")
		)
		(fp_line
			(start 0.7874 -0.4064)
			(end 0.7874 0.4064)
			(stroke
				(width 0.1524)
				(type default)
			)
			(layer "F.SilkS")
		)
		(fp_line
			(start 0.7874 0.4064)
			(end -0.7874 0.4064)
			(stroke
				(width 0.1524)
				(type default)
			)
			(layer "F.SilkS")
		)
		(fp_poly
			(pts
				(xy -0.5334 0.254) (xy -0.635 0.254) (xy -0.635 0.2286) (xy -0.635 -0.254) (xy -0.5334 -0.254) (xy -0.5334 -0.2794)
				(xy 0.5334 -0.2794) (xy 0.5334 -0.254) (xy 0.635 -0.254) (xy 0.635 0.254) (xy 0.5334 0.254) (xy 0.5334 0.2794)
				(xy -0.508 0.2794) (xy -0.5334 0.2794)
			)
			(stroke
				(width 0)
				(type default)
			)
			(fill no)
			(layer "F.CrtYd")
		)
		(pad "1" smd rect
			(at 0.40005 0)
			(size 0.4572 0.508)
			(layers "F.Cu" "F.Mask" "F.Paste")
			(net "P5V_STB_NODE1")
		)
		(pad "2" smd rect
			(at -0.40005 0)
			(size 0.4572 0.508)
			(layers "F.Cu" "F.Mask" "F.Paste")
			(net "GND")
		)
	)
	(footprint ""
		(layer "F.Cu")
		(at 190.627 -125.095 180)
		(property "Reference" "R1270"
			(at -1.27 0.10033 0)
			(unlocked yes)
			(layer "F.SilkS")
			(effects
				(font
					(size 0.7874 0.5842)
					(thickness 0.1524)
				)
				(justify left)
			)
		)
		(property "Value" ""
			(at 0 0 180)
			(layer "F.Fab")
			(effects
				(font
					(size 1.27 1.27)
				)
			)
		)
		(duplicate_pad_numbers_are_jumpers no)
		(fp_line
			(start 0.7874 0.4064)
			(end -0.7874 0.4064)
			(stroke
				(width 0.1524)
				(type default)
			)
			(layer "F.SilkS")
		)
		(fp_line
			(start 0.7874 -0.4064)
			(end 0.7874 0.4064)
			(stroke
				(width 0.1524)
				(type default)
			)
			(layer "F.SilkS")
		)
		(fp_line
			(start -0.7874 0.4064)
			(end -0.7874 -0.4064)
			(stroke
				(width 0.1524)
				(type default)
			)
			(layer "F.SilkS")
		)
		(fp_line
			(start -0.7874 -0.4064)
			(end 0.7874 -0.4064)
			(stroke
				(width 0.1524)
				(type default)
			)
			(layer "F.SilkS")
		)
		(fp_poly
			(pts
				(xy -0.508 0.2794) (xy -0.508 0.2286) (xy -0.635 0.2286) (xy -0.635 -0.254) (xy -0.5334 -0.254)
				(xy -0.5334 -0.2794) (xy 0.5334 -0.2794) (xy 0.5334 -0.254) (xy 0.635 -0.254) (xy 0.635 0.254) (xy 0.5334 0.254)
				(xy 0.5334 0.2794)
			)
			(stroke
				(width 0)
				(type default)
			)
			(fill no)
			(layer "F.CrtYd")
		)
		(pad "1" smd rect
			(at 0.40005 0 180)
			(size 0.4572 0.508)
			(layers "F.Cu" "F.Mask" "F.Paste")
			(net "SIO_JTAG_CPLD1_TCK")
		)
		(pad "2" smd rect
			(at -0.40005 0 180)
			(size 0.4572 0.508)
			(layers "F.Cu" "F.Mask" "F.Paste")
			(net "GND")
		)
	)
	(footprint ""
		(layer "F.Cu")
		(at 68.223384 -113.521744 180)
		(property "Reference" "C847"
			(at 0.308864 1.195324 0)
			(unlocked yes)
			(layer "F.SilkS")
			(effects
				(font
					(size 0.7874 0.5842)
					(thickness 0.1524)
				)
			)
		)
		(property "Value" ""
			(at 0 0 180)
			(layer "F.Fab")
			(effects
				(font
					(size 1.27 1.27)
				)
			)
		)
		(duplicate_pad_numbers_are_jumpers no)
		(fp_line
			(start 1.2954 0.5842)
			(end -1.2954 0.5842)
			(stroke
				(width 0.1524)
				(type default)
			)
			(layer "F.SilkS")
		)
		(fp_line
			(start 1.2954 -0.5842)
			(end 1.2954 0.5842)
			(stroke
				(width 0.1524)
				(type default)
			)
			(layer "F.SilkS")
		)
		(fp_line
			(start 0 -0.5842)
			(end 0 0.5842)
			(stroke
				(width 0.1524)
				(type default)
			)
			(layer "F.SilkS")
		)
		(fp_line
			(start -1.2954 0.5842)
			(end -1.2954 -0.5842)
			(stroke
				(width 0.1524)
				(type default)
			)
			(layer "F.SilkS")
		)
		(fp_line
			(start -1.2954 -0.5842)
			(end 1.2954 -0.5842)
			(stroke
				(width 0.1524)
				(type default)
			)
			(layer "F.SilkS")
		)
		(fp_poly
			(pts
				(xy 0.8636 -0.4572) (xy 0.8636 -0.3556) (xy 1.143 -0.3556) (xy 1.143 0.3556) (xy 0.8636 0.3556)
				(xy 0.8636 0.4572) (xy -0.8636 0.4572) (xy -0.8636 0.3556) (xy -1.143 0.3556) (xy -1.143 -0.3556)
				(xy -0.8636 -0.3556) (xy -0.8636 -0.4572)
			)
			(stroke
				(width 0)
				(type default)
			)
			(fill no)
			(layer "F.CrtYd")
		)
		(fp_line
			(start 0.884936 0.504952)
			(end -0.884936 0.504952)
			(stroke
				(width 0.1)
				(type default)
			)
			(layer "F.Fab")
		)
		(fp_line
			(start 0.884936 -0.504952)
			(end 0.884936 0.504952)
			(stroke
				(width 0.1)
				(type default)
			)
			(layer "F.Fab")
		)
		(fp_line
			(start -0.884936 0.504952)
			(end -0.884936 -0.504952)
			(stroke
				(width 0.1)
				(type default)
			)
			(layer "F.Fab")
		)
		(fp_line
			(start -0.884936 -0.504952)
			(end 0.884936 -0.504952)
			(stroke
				(width 0.1)
				(type default)
			)
			(layer "F.Fab")
		)
		(pad "1" smd rect
			(at 0.7366 0 270)
			(size 0.7112 0.8128)
			(layers "F.Cu" "F.Mask" "F.Paste")
			(net "FM_CPLD_NODE1_P1V8_EN_LV")
		)
		(pad "2" smd rect
			(at -0.7366 0 270)
			(size 0.7112 0.8128)
			(layers "F.Cu" "F.Mask" "F.Paste")
			(net "P1V8_NODE1")
		)
	)
	(footprint ""
		(layer "F.Cu")
		(at 93.352874 -162.206178 90)
		(property "Reference" "C886"
			(at -72.56145 87.642446 0)
			(unlocked yes)
			(layer "F.SilkS")
			(effects
				(font
					(size 0.7874 0.5842)
					(thickness 0.1524)
				)
			)
		)
		(property "Value" ""
			(at 0 0 90)
			(layer "F.Fab")
			(effects
				(font
					(size 1.27 1.27)
				)
			)
		)
		(duplicate_pad_numbers_are_jumpers no)
		(fp_line
			(start 1.2954 -0.5842)
			(end 1.2954 0.5842)
			(stroke
				(width 0.1524)
				(type default)
			)
			(layer "F.SilkS")
		)
		(fp_line
			(start 0 -0.5842)
			(end 0 0.5842)
			(stroke
				(width 0.1524)
				(type default)
			)
			(layer "F.SilkS")
		)
		(fp_line
			(start -1.2954 -0.5842)
			(end 1.2954 -0.5842)
			(stroke
				(width 0.1524)
				(type default)
			)
			(layer "F.SilkS")
		)
		(fp_line
			(start 1.2954 0.5842)
			(end -1.2954 0.5842)
			(stroke
				(width 0.1524)
				(type default)
			)
			(layer "F.SilkS")
		)
		(fp_line
			(start -1.2954 0.5842)
			(end -1.2954 -0.5842)
			(stroke
				(width 0.1524)
				(type default)
			)
			(layer "F.SilkS")
		)
		(fp_poly
			(pts
				(xy 0.8636 -0.4572) (xy 0.8636 -0.3556) (xy 1.143 -0.3556) (xy 1.143 0.3556) (xy 0.8636 0.3556)
				(xy 0.8636 0.4572) (xy -0.8636 0.4572) (xy -0.8636 0.3556) (xy -1.143 0.3556) (xy -1.143 -0.3556)
				(xy -0.8636 -0.3556) (xy -0.8636 -0.4572)
			)
			(stroke
				(width 0)
				(type default)
			)
			(fill no)
			(layer "F.CrtYd")
		)
		(fp_line
			(start 0.884936 -0.504952)
			(end 0.884936 0.504952)
			(stroke
				(width 0.1)
				(type default)
			)
			(layer "F.Fab")
		)
		(fp_line
			(start -0.884936 -0.504952)
			(end 0.884936 -0.504952)
			(stroke
				(width 0.1)
				(type default)
			)
			(layer "F.Fab")
		)
		(fp_line
			(start 0.884936 0.504952)
			(end -0.884936 0.504952)
			(stroke
				(width 0.1)
				(type default)
			)
			(layer "F.Fab")
		)
		(fp_line
			(start -0.884936 0.504952)
			(end -0.884936 -0.504952)
			(stroke
				(width 0.1)
				(type default)
			)
			(layer "F.Fab")
		)
		(pad "1" smd rect
			(at 0.7366 0 180)
			(size 0.7112 0.8128)
			(layers "F.Cu" "F.Mask" "F.Paste")
			(net "GND")
		)
		(pad "2" smd rect
			(at -0.7366 0 180)
			(size 0.7112 0.8128)
			(layers "F.Cu" "F.Mask" "F.Paste")
			(net "N52410998")
		)
	)
	(footprint ""
		(layer "F.Cu")
		(at 171.09313 -47.055786)
		(property "Reference" "C535"
			(at -3.938524 1.129538 0)
			(unlocked yes)
			(layer "F.SilkS")
			(effects
				(font
					(size 0.7874 0.5842)
					(thickness 0.1524)
				)
				(justify left)
			)
		)
		(property "Value" ""
			(at 0 0 0)
			(layer "F.Fab")
			(effects
				(font
					(size 1.27 1.27)
				)
			)
		)
		(duplicate_pad_numbers_are_jumpers no)
		(fp_line
			(start -0.7874 -0.4064)
			(end 0.7874 -0.4064)
			(stroke
				(width 0.1524)
				(type default)
			)
			(layer "F.SilkS")
		)
		(fp_line
			(start -0.7874 0.4064)
			(end -0.7874 -0.4064)
			(stroke
				(width 0.1524)
				(type default)
			)
			(layer "F.SilkS")
		)
		(fp_line
			(start 0 0.381)
			(end 0 -0.381)
			(stroke
				(width 0.1524)
				(type default)
			)
			(layer "F.SilkS")
		)
		(fp_line
			(start 0.7874 -0.4064)
			(end 0.7874 0.4064)
			(stroke
				(width 0.1524)
				(type default)
			)
			(layer "F.SilkS")
		)
		(fp_line
			(start 0.7874 0.4064)
			(end -0.7874 0.4064)
			(stroke
				(width 0.1524)
				(type default)
			)
			(layer "F.SilkS")
		)
		(fp_poly
			(pts
				(xy -0.5334 0.254) (xy -0.635 0.254) (xy -0.635 0.2286) (xy -0.635 -0.254) (xy -0.5334 -0.254) (xy -0.5334 -0.2794)
				(xy 0.5334 -0.2794) (xy 0.5334 -0.254) (xy 0.635 -0.254) (xy 0.635 0.254) (xy 0.5334 0.254) (xy 0.5334 0.2794)
				(xy -0.508 0.2794) (xy -0.5334 0.2794)
			)
			(stroke
				(width 0)
				(type default)
			)
			(fill no)
			(layer "F.CrtYd")
		)
		(pad "1" smd rect
			(at 0.40005 0)
			(size 0.4572 0.508)
			(layers "F.Cu" "F.Mask" "F.Paste")
			(net "P5V_NODE1")
		)
		(pad "2" smd rect
			(at -0.40005 0)
			(size 0.4572 0.508)
			(layers "F.Cu" "F.Mask" "F.Paste")
			(net "GND")
		)
	)
	(footprint ""
		(layer "F.Cu")
		(at 169.649394 -37.954712)
		(property "Reference" "R264"
			(at -1.495806 2.202942 0)
			(unlocked yes)
			(layer "F.SilkS")
			(effects
				(font
					(size 0.7874 0.5842)
					(thickness 0.1524)
				)
				(justify left)
			)
		)
		(property "Value" ""
			(at 0 0 0)
			(layer "F.Fab")
			(effects
				(font
					(size 1.27 1.27)
				)
			)
		)
		(duplicate_pad_numbers_are_jumpers no)
		(fp_line
			(start -0.7874 -0.4064)
			(end 0.7874 -0.4064)
			(stroke
				(width 0.1524)
				(type default)
			)
			(layer "F.SilkS")
		)
		(fp_line
			(start -0.7874 0.4064)
			(end -0.7874 -0.4064)
			(stroke
				(width 0.1524)
				(type default)
			)
			(layer "F.SilkS")
		)
		(fp_line
			(start 0.7874 -0.4064)
			(end 0.7874 0.4064)
			(stroke
				(width 0.1524)
				(type default)
			)
			(layer "F.SilkS")
		)
		(fp_line
			(start 0.7874 0.4064)
			(end -0.7874 0.4064)
			(stroke
				(width 0.1524)
				(type default)
			)
			(layer "F.SilkS")
		)
		(fp_poly
			(pts
				(xy -0.508 0.2794) (xy -0.508 0.2286) (xy -0.635 0.2286) (xy -0.635 -0.254) (xy -0.5334 -0.254)
				(xy -0.5334 -0.2794) (xy 0.5334 -0.2794) (xy 0.5334 -0.254) (xy 0.635 -0.254) (xy 0.635 0.254) (xy 0.5334 0.254)
				(xy 0.5334 0.2794)
			)
			(stroke
				(width 0)
				(type default)
			)
			(fill no)
			(layer "F.CrtYd")
		)
		(pad "1" smd rect
			(at 0.40005 0)
			(size 0.4572 0.508)
			(layers "F.Cu" "F.Mask" "F.Paste")
			(net "USB0_L_DP")
		)
		(pad "2" smd rect
			(at -0.40005 0)
			(size 0.4572 0.508)
			(layers "F.Cu" "F.Mask" "F.Paste")
			(net "USB0_DP")
		)
	)
	(footprint ""
		(layer "F.Cu")
		(at 161.83102 -188.08192 90)
		(property "Reference" "R1222"
			(at 1.118616 1.157732 90)
			(unlocked yes)
			(layer "F.SilkS")
			(effects
				(font
					(size 0.7874 0.5842)
					(thickness 0.1524)
				)
				(justify left)
			)
		)
		(property "Value" ""
			(at 0 0 90)
			(layer "F.Fab")
			(effects
				(font
					(size 1.27 1.27)
				)
			)
		)
		(duplicate_pad_numbers_are_jumpers no)
		(fp_line
			(start 0.7874 -0.4064)
			(end 0.7874 0.4064)
			(stroke
				(width 0.1524)
				(type default)
			)
			(layer "F.SilkS")
		)
		(fp_line
			(start -0.7874 -0.4064)
			(end 0.7874 -0.4064)
			(stroke
				(width 0.1524)
				(type default)
			)
			(layer "F.SilkS")
		)
		(fp_line
			(start 0.7874 0.4064)
			(end -0.7874 0.4064)
			(stroke
				(width 0.1524)
				(type default)
			)
			(layer "F.SilkS")
		)
		(fp_line
			(start -0.7874 0.4064)
			(end -0.7874 -0.4064)
			(stroke
				(width 0.1524)
				(type default)
			)
			(layer "F.SilkS")
		)
		(fp_poly
			(pts
				(xy -0.508 0.2794) (xy -0.508 0.2286) (xy -0.635 0.2286) (xy -0.635 -0.254) (xy -0.5334 -0.254)
				(xy -0.5334 -0.2794) (xy 0.5334 -0.2794) (xy 0.5334 -0.254) (xy 0.635 -0.254) (xy 0.635 0.254) (xy 0.5334 0.254)
				(xy 0.5334 0.2794)
			)
			(stroke
				(width 0)
				(type default)
			)
			(fill no)
			(layer "F.CrtYd")
		)
		(pad "1" smd rect
			(at 0.40005 0 90)
			(size 0.4572 0.508)
			(layers "F.Cu" "F.Mask" "F.Paste")
			(net "FAN4_TACH_R")
		)
		(pad "2" smd rect
			(at -0.40005 0 90)
			(size 0.4572 0.508)
			(layers "F.Cu" "F.Mask" "F.Paste")
			(net "GND")
		)
	)
	(footprint ""
		(layer "F.Cu")
		(at 48.717962 -110.52556 90)
		(property "Reference" "PC15"
			(at 2.04216 0.080518 0)
			(unlocked yes)
			(layer "F.SilkS")
			(effects
				(font
					(size 0.7874 0.5842)
					(thickness 0.1524)
				)
				(justify left)
			)
		)
		(property "Value" ""
			(at 0 0 90)
			(layer "F.Fab")
			(effects
				(font
					(size 1.27 1.27)
				)
			)
		)
		(duplicate_pad_numbers_are_jumpers no)
		(fp_line
			(start 0.7874 -0.4064)
			(end 0.7874 0.4064)
			(stroke
				(width 0.1524)
				(type default)
			)
			(layer "F.SilkS")
		)
		(fp_line
			(start -0.7874 -0.4064)
			(end 0.7874 -0.4064)
			(stroke
				(width 0.1524)
				(type default)
			)
			(layer "F.SilkS")
		)
		(fp_line
			(start 0 0.381)
			(end 0 -0.381)
			(stroke
				(width 0.1524)
				(type default)
			)
			(layer "F.SilkS")
		)
		(fp_line
			(start 0.7874 0.4064)
			(end -0.7874 0.4064)
			(stroke
				(width 0.1524)
				(type default)
			)
			(layer "F.SilkS")
		)
		(fp_line
			(start -0.7874 0.4064)
			(end -0.7874 -0.4064)
			(stroke
				(width 0.1524)
				(type default)
			)
			(layer "F.SilkS")
		)
		(fp_poly
			(pts
				(xy -0.5334 0.254) (xy -0.635 0.254) (xy -0.635 0.2286) (xy -0.635 -0.254) (xy -0.5334 -0.254) (xy -0.5334 -0.2794)
				(xy 0.5334 -0.2794) (xy 0.5334 -0.254) (xy 0.635 -0.254) (xy 0.635 0.254) (xy 0.5334 0.254) (xy 0.5334 0.2794)
				(xy -0.508 0.2794) (xy -0.5334 0.2794)
			)
			(stroke
				(width 0)
				(type default)
			)
			(fill no)
			(layer "F.CrtYd")
		)
		(pad "1" smd rect
			(at 0.40005 0 90)
			(size 0.4572 0.508)
			(layers "F.Cu" "F.Mask" "F.Paste")
			(net "SW_P3V3_STB_NODE1_BT")
		)
		(pad "2" smd rect
			(at -0.40005 0 90)
			(size 0.4572 0.508)
			(layers "F.Cu" "F.Mask" "F.Paste")
			(net "SW_P3V3_STB_NODE1_PH")
		)
	)
)
